(kicad_pcb
	(version 20260206)
	(generator "pcbnew")
	(generator_version "10.0")
	(general
		(thickness 1.6)
		(legacy_teardrops no)
	)
	(paper "A4")
	(title_block
		(title "Wiwynn_Tioga_Pass_MB.brd")
		(comment 1 "Tioga Pass / footprints 2016-2017 of 4770")
	)
	(layers
		(0 "F.Cu" signal "TOP")
		(4 "In1.Cu" signal "L2GND")
		(6 "In2.Cu" signal "L3")
		(8 "In3.Cu" signal "L4GND")
		(10 "In4.Cu" signal "L5")
		(12 "In5.Cu" signal "L6GND")
		(14 "In6.Cu" signal "L7VCC")
		(16 "In7.Cu" signal "L8VCC")
		(18 "In8.Cu" signal "L9GND")
		(20 "In9.Cu" signal "L10")
		(22 "In10.Cu" signal "L11GND")
		(24 "In11.Cu" signal "L12")
		(26 "In12.Cu" signal "L13GND")
		(2 "B.Cu" signal "BOTTOM")
		(9 "F.Adhes" user "F.Adhesive")
		(11 "B.Adhes" user "B.Adhesive")
		(13 "F.Paste" user "Package Geometry/Pastemask Top")
		(15 "B.Paste" user "Package Geometry/Pastemask Bottom")
		(5 "F.SilkS" user "Ref Des/Silkscreen Top")
		(7 "B.SilkS" user "Ref Des/Silkscreen Bottom")
		(1 "F.Mask" user "Board Geometry/Soldermask Top")
		(3 "B.Mask" user "Board Geometry/Soldermask Bottom")
		(17 "Dwgs.User" user "User.Drawings")
		(19 "Cmts.User" user "User.Comments")
		(21 "Eco1.User" user "User.Eco1")
		(23 "Eco2.User" user "User.Eco2")
		(25 "Edge.Cuts" user "Board Geometry/Outline")
		(27 "Margin" user)
		(31 "F.CrtYd" user "Package Geometry/Place Bound Top")
		(29 "B.CrtYd" user "Package Geometry/Place Bound Bottom")
		(35 "F.Fab" user "Ref Des/Assembly Top")
		(33 "B.Fab" user "Ref Des/Assembly Bottom")
	)
	(footprint ""
		(layer "F.Cu")
		(at 269.645638 -68.365116 180)
		(property "Reference" "C5D59"
			(at 0 0 180)
			(layer "F.SilkS")
			(hide yes)
			(effects
				(font
					(size 1.27 1.27)
				)
			)
		)
		(property "Value" ""
			(at 0 0 180)
			(layer "F.Fab")
			(effects
				(font
					(size 1.27 1.27)
				)
			)
		)
		(duplicate_pad_numbers_are_jumpers no)
		(fp_poly
			(pts
				(xy -0.4953 -0.2032) (xy 0.4953 -0.2032) (xy 0.4953 1.6002) (xy -0.4953 1.6002)
			)
			(stroke
				(width 0)
				(type default)
			)
			(fill no)
			(layer "F.CrtYd")
		)
		(fp_line
			(start 0.4953 1.6002)
			(end -0.4953 1.6002)
			(stroke
				(width 0.1)
				(type default)
			)
			(layer "F.Fab")
		)
		(fp_line
			(start 0.4953 -0.2032)
			(end 0.4953 1.6002)
			(stroke
				(width 0.1)
				(type default)
			)
			(layer "F.Fab")
		)
		(fp_line
			(start -0.4953 1.6002)
			(end -0.4953 -0.2032)
			(stroke
				(width 0.1)
				(type default)
			)
			(layer "F.Fab")
		)
		(fp_line
			(start -0.4953 -0.2032)
			(end 0.4953 -0.2032)
			(stroke
				(width 0.1)
				(type default)
			)
			(layer "F.Fab")
		)
		(pad "1" smd rect
			(at 0 0 180)
			(size 0.762 0.889)
			(layers "F.Cu" "F.Mask" "F.Paste")
			(net "PVDDQ_ABC")
		)
		(pad "2" smd rect
			(at 0 1.397 180)
			(size 0.762 0.889)
			(layers "F.Cu" "F.Mask" "F.Paste")
			(net "GND")
		)
		(zone
			(layer "F.Cu")
			(hatch none 0.5)
			(connect_pads
				(clearance 0)
			)
			(min_thickness 0.25)
			(keepout
				(tracks not_allowed)
				(vias allowed)
				(pads allowed)
				(copperpour not_allowed)
				(footprints allowed)
			)
			(placement
				(enabled no)
				(sheetname "")
			)
			(fill
				(thermal_gap 0.5)
				(thermal_bridge_width 0.5)
				(island_removal_mode 0)
			)
			(polygon
				(pts
					(xy 270.026638 -68.809616) (xy 269.264638 -68.809616) (xy 269.264638 -69.317616) (xy 270.026638 -69.317616)
				)
			)
		)
	)
	(footprint ""
		(layer "F.Cu")
		(at 179.6288 -65.7606 -90)
		(property "Reference" "R4D63"
			(at 0 0 270)
			(layer "F.SilkS")
			(hide yes)
			(effects
				(font
					(size 1.27 1.27)
				)
			)
		)
		(property "Value" ""
			(at 0 0 270)
			(layer "F.Fab")
			(effects
				(font
					(size 1.27 1.27)
				)
			)
		)
		(duplicate_pad_numbers_are_jumpers no)
		(fp_poly
			(pts
				(xy -0.2794 -0.1016) (xy 0.2794 -0.1016) (xy 0.2794 0.9906) (xy -0.2794 0.9906)
			)
			(stroke
				(width 0)
				(type default)
			)
			(fill no)
			(layer "F.CrtYd")
		)
		(fp_line
			(start -0.2794 0.9906)
			(end 0.2794 0.9906)
			(stroke
				(width 0.1)
				(type default)
			)
			(layer "F.Fab")
		)
		(fp_line
			(start 0.2794 0.9906)
			(end 0.2794 -0.1016)
			(stroke
				(width 0.1)
				(type default)
			)
			(layer "F.Fab")
		)
		(fp_line
			(start -0.2794 -0.1016)
			(end -0.2794 0.9906)
			(stroke
				(width 0.1)
				(type default)
			)
			(layer "F.Fab")
		)
		(fp_line
			(start 0.2794 -0.1016)
			(end -0.2794 -0.1016)
			(stroke
				(width 0.1)
				(type default)
			)
			(layer "F.Fab")
		)
		(pad "1" smd rect
			(at 0 0 270)
			(size 0.508 0.508)
			(layers "F.Cu" "F.Mask" "F.Paste")
			(net "VR_VRRDY_PVCCIN_CPU0")
		)
		(pad "2" smd rect
			(at 0 0.889 270)
			(size 0.508 0.508)
			(layers "F.Cu" "F.Mask" "F.Paste")
			(net "PWRGD_PVCCIN_CPU0")
		)
		(zone
			(layer "F.Cu")
			(hatch none 0.5)
			(connect_pads
				(clearance 0)
			)
			(min_thickness 0.25)
			(keepout
				(tracks not_allowed)
				(vias allowed)
				(pads allowed)
				(copperpour not_allowed)
				(footprints allowed)
			)
			(placement
				(enabled no)
				(sheetname "")
			)
			(fill
				(thermal_gap 0.5)
				(thermal_bridge_width 0.5)
				(island_removal_mode 0)
			)
			(polygon
				(pts
					(xy 178.9938 -66.0146) (xy 178.9938 -65.5066) (xy 179.3748 -65.5066) (xy 179.3748 -66.0146)
				)
			)
		)
		(zone
			(layer "F.Cu")
			(hatch none 0.5)
			(connect_pads
				(clearance 0)
			)
			(min_thickness 0.25)
			(keepout
				(tracks allowed)
				(vias not_allowed)
				(pads allowed)
				(copperpour not_allowed)
				(footprints allowed)
			)
			(placement
				(enabled no)
				(sheetname "")
			)
			(fill
				(thermal_gap 0.5)
				(thermal_bridge_width 0.5)
				(island_removal_mode 0)
			)
			(polygon
				(pts
					(xy 179.3748 -66.0146) (xy 179.3748 -65.5066) (xy 178.9938 -65.5066) (xy 178.9938 -66.0146)
				)
			)
		)
	)
)
